(kicad_pcb
	(version 20260206)
	(generator "pcbnew")
	(generator_version "10.0")
	(general
		(thickness 1.6)
		(legacy_teardrops no)
	)
	(paper "A4")
	(title_block
		(title "Wiwynn_Tioga_Pass_MB.brd")
		(comment 1 "Tioga Pass / footprints 2705-2712 of 4770")
	)
	(layers
		(0 "F.Cu" signal "TOP")
		(4 "In1.Cu" signal "L2GND")
		(6 "In2.Cu" signal "L3")
		(8 "In3.Cu" signal "L4GND")
		(10 "In4.Cu" signal "L5")
		(12 "In5.Cu" signal "L6GND")
		(14 "In6.Cu" signal "L7VCC")
		(16 "In7.Cu" signal "L8VCC")
		(18 "In8.Cu" signal "L9GND")
		(20 "In9.Cu" signal "L10")
		(22 "In10.Cu" signal "L11GND")
		(24 "In11.Cu" signal "L12")
		(26 "In12.Cu" signal "L13GND")
		(2 "B.Cu" signal "BOTTOM")
		(9 "F.Adhes" user "F.Adhesive")
		(11 "B.Adhes" user "B.Adhesive")
		(13 "F.Paste" user "Package Geometry/Pastemask Top")
		(15 "B.Paste" user "Package Geometry/Pastemask Bottom")
		(5 "F.SilkS" user "Ref Des/Silkscreen Top")
		(7 "B.SilkS" user "Ref Des/Silkscreen Bottom")
		(1 "F.Mask" user "Board Geometry/Soldermask Top")
		(3 "B.Mask" user "Board Geometry/Soldermask Bottom")
		(17 "Dwgs.User" user "User.Drawings")
		(19 "Cmts.User" user "User.Comments")
		(21 "Eco1.User" user "User.Eco1")
		(23 "Eco2.User" user "User.Eco2")
		(25 "Edge.Cuts" user "Board Geometry/Outline")
		(27 "Margin" user)
		(31 "F.CrtYd" user "Package Geometry/Place Bound Top")
		(29 "B.CrtYd" user "Package Geometry/Place Bound Bottom")
		(35 "F.Fab" user "Ref Des/Assembly Top")
		(33 "B.Fab" user "Ref Des/Assembly Bottom")
	)
	(footprint ""
		(layer "B.Cu")
		(at 486.156 -113.2332 -90)
		(property "Reference" "C1M23"
			(at 0 0 90)
			(layer "B.SilkS")
			(hide yes)
			(effects
				(font
					(size 1.27 1.27)
				)
				(justify mirror)
			)
		)
		(property "Value" ""
			(at 0 0 90)
			(layer "B.Fab")
			(effects
				(font
					(size 1.27 1.27)
				)
				(justify mirror)
			)
		)
		(duplicate_pad_numbers_are_jumpers no)
		(fp_rect
			(start 0.3048 0.9906)
			(end -0.3048 -0.1016)
			(stroke
				(width 0)
				(type default)
			)
			(fill no)
			(layer "B.CrtYd")
		)
		(fp_line
			(start -0.3048 0.9906)
			(end -0.3048 -0.1016)
			(stroke
				(width 0.1)
				(type default)
			)
			(layer "B.Fab")
		)
		(fp_line
			(start 0.3048 0.9906)
			(end -0.3048 0.9906)
			(stroke
				(width 0.1)
				(type default)
			)
			(layer "B.Fab")
		)
		(fp_line
			(start -0.3048 -0.1016)
			(end 0.3048 -0.1016)
			(stroke
				(width 0.1)
				(type default)
			)
			(layer "B.Fab")
		)
		(fp_line
			(start 0.3048 -0.1016)
			(end 0.3048 0.9906)
			(stroke
				(width 0.1)
				(type default)
			)
			(layer "B.Fab")
		)
		(pad "1" smd rect
			(at 0 0 90)
			(size 0.508 0.508)
			(layers "B.Cu" "B.Mask" "B.Paste")
			(net "P12V_STBY")
		)
		(pad "2" smd rect
			(at 0 0.889 90)
			(size 0.508 0.508)
			(layers "B.Cu" "B.Mask" "B.Paste")
			(net "GND")
		)
		(zone
			(layer "B.Cu")
			(hatch none 0.5)
			(connect_pads
				(clearance 0)
			)
			(min_thickness 0.25)
			(keepout
				(tracks allowed)
				(vias not_allowed)
				(pads allowed)
				(copperpour not_allowed)
				(footprints allowed)
			)
			(placement
				(enabled no)
				(sheetname "")
			)
			(fill
				(thermal_gap 0.5)
				(thermal_bridge_width 0.5)
				(island_removal_mode 0)
			)
			(polygon
				(pts
					(xy 485.521 -112.9792) (xy 485.902 -112.9792) (xy 485.902 -113.4872) (xy 485.521 -113.4872)
				)
			)
		)
		(zone
			(layer "B.Cu")
			(hatch none 0.5)
			(connect_pads
				(clearance 0)
			)
			(min_thickness 0.25)
			(keepout
				(tracks not_allowed)
				(vias allowed)
				(pads allowed)
				(copperpour not_allowed)
				(footprints allowed)
			)
			(placement
				(enabled no)
				(sheetname "")
			)
			(fill
				(thermal_gap 0.5)
				(thermal_bridge_width 0.5)
				(island_removal_mode 0)
			)
			(polygon
				(pts
					(xy 485.521 -112.9792) (xy 485.902 -112.9792) (xy 485.902 -113.4872) (xy 485.521 -113.4872)
				)
			)
		)
	)
	(footprint ""
		(layer "B.Cu")
		(at 424.200574 -40.982646 180)
		(property "Reference" "C25W56"
			(at 0.8382 -0.67818 180)
			(unlocked yes)
			(layer "B.SilkS")
			(effects
				(font
					(size 0.4064 0.254)
					(thickness 0.1524)
				)
				(justify left mirror)
			)
		)
		(property "Value" ""
			(at 0 0 0)
			(layer "B.Fab")
			(effects
				(font
					(size 1.27 1.27)
				)
				(justify mirror)
			)
		)
		(duplicate_pad_numbers_are_jumpers no)
		(fp_poly
			(pts
				(xy -0.3048 -0.1016) (xy -0.3048 0.9906) (xy 0.3048 0.9906) (xy 0.3048 -0.1016)
			)
			(stroke
				(width 0)
				(type default)
			)
			(fill no)
			(layer "B.CrtYd")
		)
		(fp_line
			(start 0.3048 0.9906)
			(end -0.3048 0.9906)
			(stroke
				(width 0.1)
				(type default)
			)
			(layer "B.Fab")
		)
		(fp_line
			(start 0.3048 -0.1016)
			(end 0.3048 0.9906)
			(stroke
				(width 0.1)
				(type default)
			)
			(layer "B.Fab")
		)
		(fp_line
			(start -0.3048 0.9906)
			(end -0.3048 -0.1016)
			(stroke
				(width 0.1)
				(type default)
			)
			(layer "B.Fab")
		)
		(fp_line
			(start -0.3048 -0.1016)
			(end 0.3048 -0.1016)
			(stroke
				(width 0.1)
				(type default)
			)
			(layer "B.Fab")
		)
		(pad "1" smd rect
			(at 0 0)
			(size 0.508 0.508)
			(layers "B.Cu" "B.Mask" "B.Paste")
			(net "VCC_PA_3V3")
		)
		(pad "2" smd rect
			(at 0 0.889)
			(size 0.508 0.508)
			(layers "B.Cu" "B.Mask" "B.Paste")
			(net "GND")
		)
		(zone
			(layer "B.Cu")
			(hatch none 0.5)
			(connect_pads
				(clearance 0)
			)
			(min_thickness 0.25)
			(keepout
				(tracks not_allowed)
				(vias allowed)
				(pads allowed)
				(copperpour not_allowed)
				(footprints allowed)
			)
			(placement
				(enabled no)
				(sheetname "")
			)
			(fill
				(thermal_gap 0.5)
				(thermal_bridge_width 0.5)
				(island_removal_mode 0)
			)
			(polygon
				(pts
					(xy 423.946574 -41.617646) (xy 424.454574 -41.617646) (xy 424.454574 -41.236646) (xy 423.946574 -41.236646)
				)
			)
		)
		(zone
			(layer "B.Cu")
			(hatch none 0.5)
			(connect_pads
				(clearance 0)
			)
			(min_thickness 0.25)
			(keepout
				(tracks allowed)
				(vias not_allowed)
				(pads allowed)
				(copperpour not_allowed)
				(footprints allowed)
			)
			(placement
				(enabled no)
				(sheetname "")
			)
			(fill
				(thermal_gap 0.5)
				(thermal_bridge_width 0.5)
				(island_removal_mode 0)
			)
			(polygon
				(pts
					(xy 423.946574 -41.236646) (xy 424.454574 -41.236646) (xy 424.454574 -41.617646) (xy 423.946574 -41.617646)
				)
			)
		)
	)
	(footprint ""
		(layer "B.Cu")
		(at 295.153588 -66.330322 90)
		(property "Reference" "R4P21"
			(at 0 0 90)
			(layer "B.SilkS")
			(hide yes)
			(effects
				(font
					(size 1.27 1.27)
				)
				(justify mirror)
			)
		)
		(property "Value" ""
			(at 0 0 90)
			(layer "B.Fab")
			(effects
				(font
					(size 1.27 1.27)
				)
				(justify mirror)
			)
		)
		(duplicate_pad_numbers_are_jumpers no)
		(fp_poly
			(pts
				(xy 0.2794 -0.1016) (xy -0.2794 -0.1016) (xy -0.2794 0.9906) (xy 0.2794 0.9906)
			)
			(stroke
				(width 0)
				(type default)
			)
			(fill no)
			(layer "B.CrtYd")
		)
		(fp_line
			(start 0.2794 -0.1016)
			(end 0.2794 0.9906)
			(stroke
				(width 0.1)
				(type default)
			)
			(layer "B.Fab")
		)
		(fp_line
			(start -0.2794 -0.1016)
			(end 0.2794 -0.1016)
			(stroke
				(width 0.1)
				(type default)
			)
			(layer "B.Fab")
		)
		(fp_line
			(start 0.2794 0.9906)
			(end -0.2794 0.9906)
			(stroke
				(width 0.1)
				(type default)
			)
			(layer "B.Fab")
		)
		(fp_line
			(start -0.2794 0.9906)
			(end -0.2794 -0.1016)
			(stroke
				(width 0.1)
				(type default)
			)
			(layer "B.Fab")
		)
		(pad "1" smd rect
			(at 0 0 270)
			(size 0.508 0.508)
			(layers "B.Cu" "B.Mask" "B.Paste")
			(net "PVCCIO_CPU0")
		)
		(pad "2" smd rect
			(at 0 0.889 270)
			(size 0.508 0.508)
			(layers "B.Cu" "B.Mask" "B.Paste")
			(net "PU_CPU0_TSC_SYNC")
		)
		(zone
			(layer "B.Cu")
			(hatch none 0.5)
			(connect_pads
				(clearance 0)
			)
			(min_thickness 0.25)
			(keepout
				(tracks allowed)
				(vias not_allowed)
				(pads allowed)
				(copperpour not_allowed)
				(footprints allowed)
			)
			(placement
				(enabled no)
				(sheetname "")
			)
			(fill
				(thermal_gap 0.5)
				(thermal_bridge_width 0.5)
				(island_removal_mode 0)
			)
			(polygon
				(pts
					(xy 295.407588 -66.584322) (xy 295.407588 -66.076322) (xy 295.788588 -66.076322) (xy 295.788588 -66.584322)
				)
			)
		)
		(zone
			(layer "B.Cu")
			(hatch none 0.5)
			(connect_pads
				(clearance 0)
			)
			(min_thickness 0.25)
			(keepout
				(tracks not_allowed)
				(vias allowed)
				(pads allowed)
				(copperpour not_allowed)
				(footprints allowed)
			)
			(placement
				(enabled no)
				(sheetname "")
			)
			(fill
				(thermal_gap 0.5)
				(thermal_bridge_width 0.5)
				(island_removal_mode 0)
			)
			(polygon
				(pts
					(xy 295.788588 -66.584322) (xy 295.788588 -66.076322) (xy 295.407588 -66.076322) (xy 295.407588 -66.584322)
				)
			)
		)
	)
	(footprint ""
		(layer "B.Cu")
		(at 93.081348 -135.3312 -90)
		(property "Reference" "C8M8"
			(at 0 0 90)
			(layer "B.SilkS")
			(hide yes)
			(effects
				(font
					(size 1.27 1.27)
				)
				(justify mirror)
			)
		)
		(property "Value" ""
			(at 0 0 90)
			(layer "B.Fab")
			(effects
				(font
					(size 1.27 1.27)
				)
				(justify mirror)
			)
		)
		(duplicate_pad_numbers_are_jumpers no)
		(fp_rect
			(start 0.500126 1.598422)
			(end -0.500126 -0.201422)
			(stroke
				(width 0)
				(type default)
			)
			(fill no)
			(layer "B.CrtYd")
		)
		(fp_line
			(start -0.500126 1.598422)
			(end 0.500126 1.598422)
			(stroke
				(width 0.1)
				(type default)
			)
			(layer "B.Fab")
		)
		(fp_line
			(start 0.500126 1.598422)
			(end 0.500126 -0.201422)
			(stroke
				(width 0.1)
				(type default)
			)
			(layer "B.Fab")
		)
		(fp_line
			(start -0.500126 -0.201422)
			(end -0.500126 1.598422)
			(stroke
				(width 0.1)
				(type default)
			)
			(layer "B.Fab")
		)
		(fp_line
			(start 0.500126 -0.201422)
			(end -0.500126 -0.201422)
			(stroke
				(width 0.1)
				(type default)
			)
			(layer "B.Fab")
		)
		(pad "1" smd rect
			(at 0 0 180)
			(size 0.889 0.9906)
			(layers "B.Cu" "B.Mask" "B.Paste")
			(net "PVDDQ_KLM")
		)
		(pad "2" smd rect
			(at 0 1.397 180)
			(size 0.889 0.9906)
			(layers "B.Cu" "B.Mask" "B.Paste")
			(net "GND")
		)
		(zone
			(layer "B.Cu")
			(hatch none 0.5)
			(connect_pads
				(clearance 0)
			)
			(min_thickness 0.25)
			(keepout
				(tracks not_allowed)
				(vias allowed)
				(pads allowed)
				(copperpour not_allowed)
				(footprints allowed)
			)
			(placement
				(enabled no)
				(sheetname "")
			)
			(fill
				(thermal_gap 0.5)
				(thermal_bridge_width 0.5)
				(island_removal_mode 0)
			)
			(polygon
				(pts
					(xy 92.128848 -134.8359) (xy 92.636848 -134.8359) (xy 92.636848 -135.8265) (xy 92.128848 -135.8265)
				)
			)
		)
		(zone
			(layer "B.Cu")
			(hatch none 0.5)
			(connect_pads
				(clearance 0)
			)
			(min_thickness 0.25)
			(keepout
				(tracks allowed)
				(vias not_allowed)
				(pads allowed)
				(copperpour not_allowed)
				(footprints allowed)
			)
			(placement
				(enabled no)
				(sheetname "")
			)
			(fill
				(thermal_gap 0.5)
				(thermal_bridge_width 0.5)
				(island_removal_mode 0)
			)
			(polygon
				(pts
					(xy 92.128848 -134.8359) (xy 92.636848 -134.8359) (xy 92.636848 -135.8265) (xy 92.128848 -135.8265)
				)
			)
		)
	)
	(footprint ""
		(layer "B.Cu")
		(at 360.555794 -41.543986 90)
		(property "Reference" "R2T58"
			(at 0 0 90)
			(layer "B.SilkS")
			(hide yes)
			(effects
				(font
					(size 1.27 1.27)
				)
				(justify mirror)
			)
		)
		(property "Value" ""
			(at 0 0 90)
			(layer "B.Fab")
			(effects
				(font
					(size 1.27 1.27)
				)
				(justify mirror)
			)
		)
		(duplicate_pad_numbers_are_jumpers no)
		(fp_poly
			(pts
				(xy 0.2794 -0.1016) (xy -0.2794 -0.1016) (xy -0.2794 0.9906) (xy 0.2794 0.9906)
			)
			(stroke
				(width 0)
				(type default)
			)
			(fill no)
			(layer "B.CrtYd")
		)
		(fp_line
			(start 0.2794 -0.1016)
			(end 0.2794 0.9906)
			(stroke
				(width 0.1)
				(type default)
			)
			(layer "B.Fab")
		)
		(fp_line
			(start -0.2794 -0.1016)
			(end 0.2794 -0.1016)
			(stroke
				(width 0.1)
				(type default)
			)
			(layer "B.Fab")
		)
		(fp_line
			(start 0.2794 0.9906)
			(end -0.2794 0.9906)
			(stroke
				(width 0.1)
				(type default)
			)
			(layer "B.Fab")
		)
		(fp_line
			(start -0.2794 0.9906)
			(end -0.2794 -0.1016)
			(stroke
				(width 0.1)
				(type default)
			)
			(layer "B.Fab")
		)
		(pad "1" smd rect
			(at 0 0 270)
			(size 0.508 0.508)
			(layers "B.Cu" "B.Mask" "B.Paste")
			(net "H_CPU_ERR0_PCH_N")
		)
		(pad "2" smd rect
			(at 0 0.889 270)
			(size 0.508 0.508)
			(layers "B.Cu" "B.Mask" "B.Paste")
			(net "FM_CPU_ERR0_LVT3_K_N")
		)
		(zone
			(layer "B.Cu")
			(hatch none 0.5)
			(connect_pads
				(clearance 0)
			)
			(min_thickness 0.25)
			(keepout
				(tracks allowed)
				(vias not_allowed)
				(pads allowed)
				(copperpour not_allowed)
				(footprints allowed)
			)
			(placement
				(enabled no)
				(sheetname "")
			)
			(fill
				(thermal_gap 0.5)
				(thermal_bridge_width 0.5)
				(island_removal_mode 0)
			)
			(polygon
				(pts
					(xy 360.809794 -41.797986) (xy 360.809794 -41.289986) (xy 361.190794 -41.289986) (xy 361.190794 -41.797986)
				)
			)
		)
		(zone
			(layer "B.Cu")
			(hatch none 0.5)
			(connect_pads
				(clearance 0)
			)
			(min_thickness 0.25)
			(keepout
				(tracks not_allowed)
				(vias allowed)
				(pads allowed)
				(copperpour not_allowed)
				(footprints allowed)
			)
			(placement
				(enabled no)
				(sheetname "")
			)
			(fill
				(thermal_gap 0.5)
				(thermal_bridge_width 0.5)
				(island_removal_mode 0)
			)
			(polygon
				(pts
					(xy 361.190794 -41.797986) (xy 361.190794 -41.289986) (xy 360.809794 -41.289986) (xy 360.809794 -41.797986)
				)
			)
		)
	)
	(footprint ""
		(layer "B.Cu")
		(at 176.149 -76.327 -90)
		(property "Reference" "R6P17"
			(at 0 0 90)
			(layer "B.SilkS")
			(hide yes)
			(effects
				(font
					(size 1.27 1.27)
				)
				(justify mirror)
			)
		)
		(property "Value" ""
			(at 0 0 90)
			(layer "B.Fab")
			(effects
				(font
					(size 1.27 1.27)
				)
				(justify mirror)
			)
		)
		(duplicate_pad_numbers_are_jumpers no)
		(fp_poly
			(pts
				(xy 0.2794 -0.1016) (xy -0.2794 -0.1016) (xy -0.2794 0.9906) (xy 0.2794 0.9906)
			)
			(stroke
				(width 0)
				(type default)
			)
			(fill no)
			(layer "B.CrtYd")
		)
		(fp_line
			(start -0.2794 0.9906)
			(end -0.2794 -0.1016)
			(stroke
				(width 0.1)
				(type default)
			)
			(layer "B.Fab")
		)
		(fp_line
			(start 0.2794 0.9906)
			(end -0.2794 0.9906)
			(stroke
				(width 0.1)
				(type default)
			)
			(layer "B.Fab")
		)
		(fp_line
			(start -0.2794 -0.1016)
			(end 0.2794 -0.1016)
			(stroke
				(width 0.1)
				(type default)
			)
			(layer "B.Fab")
		)
		(fp_line
			(start 0.2794 -0.1016)
			(end 0.2794 0.9906)
			(stroke
				(width 0.1)
				(type default)
			)
			(layer "B.Fab")
		)
		(pad "1" smd rect
			(at 0 0 90)
			(size 0.508 0.508)
			(layers "B.Cu" "B.Mask" "B.Paste")
			(net "CLK_100M_CPU0_BCLK0_DP")
		)
		(pad "2" smd rect
			(at 0 0.889 90)
			(size 0.508 0.508)
			(layers "B.Cu" "B.Mask" "B.Paste")
			(net "GND")
		)
		(zone
			(layer "B.Cu")
			(hatch none 0.5)
			(connect_pads
				(clearance 0)
			)
			(min_thickness 0.25)
			(keepout
				(tracks not_allowed)
				(vias allowed)
				(pads allowed)
				(copperpour not_allowed)
				(footprints allowed)
			)
			(placement
				(enabled no)
				(sheetname "")
			)
			(fill
				(thermal_gap 0.5)
				(thermal_bridge_width 0.5)
				(island_removal_mode 0)
			)
			(polygon
				(pts
					(xy 175.514 -76.073) (xy 175.514 -76.581) (xy 175.895 -76.581) (xy 175.895 -76.073)
				)
			)
		)
		(zone
			(layer "B.Cu")
			(hatch none 0.5)
			(connect_pads
				(clearance 0)
			)
			(min_thickness 0.25)
			(keepout
				(tracks allowed)
				(vias not_allowed)
				(pads allowed)
				(copperpour not_allowed)
				(footprints allowed)
			)
			(placement
				(enabled no)
				(sheetname "")
			)
			(fill
				(thermal_gap 0.5)
				(thermal_bridge_width 0.5)
				(island_removal_mode 0)
			)
			(polygon
				(pts
					(xy 175.895 -76.073) (xy 175.895 -76.581) (xy 175.514 -76.581) (xy 175.514 -76.073)
				)
			)
		)
	)
	(footprint ""
		(layer "B.Cu")
		(at 457.5048 -52.483258)
		(property "Reference" "C1R5"
			(at 0 0 0)
			(layer "B.SilkS")
			(hide yes)
			(effects
				(font
					(size 1.27 1.27)
				)
				(justify mirror)
			)
		)
		(property "Value" ""
			(at 0 0 0)
			(layer "B.Fab")
			(effects
				(font
					(size 1.27 1.27)
				)
				(justify mirror)
			)
		)
		(duplicate_pad_numbers_are_jumpers no)
		(fp_poly
			(pts
				(xy -0.3048 -0.1016) (xy -0.3048 0.9906) (xy 0.3048 0.9906) (xy 0.3048 -0.1016)
			)
			(stroke
				(width 0)
				(type default)
			)
			(fill no)
			(layer "B.CrtYd")
		)
		(fp_line
			(start -0.3048 -0.1016)
			(end 0.3048 -0.1016)
			(stroke
				(width 0.1)
				(type default)
			)
			(layer "B.Fab")
		)
		(fp_line
			(start -0.3048 0.9906)
			(end -0.3048 -0.1016)
			(stroke
				(width 0.1)
				(type default)
			)
			(layer "B.Fab")
		)
		(fp_line
			(start 0.3048 -0.1016)
			(end 0.3048 0.9906)
			(stroke
				(width 0.1)
				(type default)
			)
			(layer "B.Fab")
		)
		(fp_line
			(start 0.3048 0.9906)
			(end -0.3048 0.9906)
			(stroke
				(width 0.1)
				(type default)
			)
			(layer "B.Fab")
		)
		(pad "1" smd rect
			(at 0 0 180)
			(size 0.508 0.508)
			(layers "B.Cu" "B.Mask" "B.Paste")
			(net "P3E_CPU0_PE3_OCP_TXN<2>")
		)
		(pad "2" smd rect
			(at 0 0.889 180)
			(size 0.508 0.508)
			(layers "B.Cu" "B.Mask" "B.Paste")
			(net "P3E_OCP_CPU0_PE3_C_TXN<2>")
		)
		(zone
			(layer "B.Cu")
			(hatch none 0.5)
			(connect_pads
				(clearance 0)
			)
			(min_thickness 0.25)
			(keepout
				(tracks allowed)
				(vias not_allowed)
				(pads allowed)
				(copperpour not_allowed)
				(footprints allowed)
			)
			(placement
				(enabled no)
				(sheetname "")
			)
			(fill
				(thermal_gap 0.5)
				(thermal_bridge_width 0.5)
				(island_removal_mode 0)
			)
			(polygon
				(pts
					(xy 457.7588 -52.229258) (xy 457.2508 -52.229258) (xy 457.2508 -51.848258) (xy 457.7588 -51.848258)
				)
			)
		)
	)
	(footprint ""
		(layer "B.Cu")
		(at 1.3462 -141.097 90)
		(property "Reference" "C9L11"
			(at 0 0 90)
			(layer "B.SilkS")
			(hide yes)
			(effects
				(font
					(size 1.27 1.27)
				)
				(justify mirror)
			)
		)
		(property "Value" ""
			(at 0 0 90)
			(layer "B.Fab")
			(effects
				(font
					(size 1.27 1.27)
				)
				(justify mirror)
			)
		)
		(duplicate_pad_numbers_are_jumpers no)
		(fp_rect
			(start -0.7239 -0.2159)
			(end 0.7239 1.9939)
			(stroke
				(width 0)
				(type default)
			)
			(fill no)
			(layer "B.CrtYd")
		)
		(fp_line
			(start 0.7239 -0.2159)
			(end 0.7239 1.9939)
			(stroke
				(width 0.1)
				(type default)
			)
			(layer "B.Fab")
		)
		(fp_line
			(start -0.7239 -0.2159)
			(end 0.7239 -0.2159)
			(stroke
				(width 0.1)
				(type default)
			)
			(layer "B.Fab")
		)
		(fp_line
			(start 0.7239 1.9939)
			(end -0.7239 1.9939)
			(stroke
				(width 0.1)
				(type default)
			)
			(layer "B.Fab")
		)
		(fp_line
			(start -0.7239 1.9939)
			(end -0.7239 -0.2159)
			(stroke
				(width 0.1)
				(type default)
			)
			(layer "B.Fab")
		)
		(pad "1" smd rect
			(at 0 0 270)
			(size 1.27 1.016)
			(layers "B.Cu" "B.Mask" "B.Paste")
			(net "VR_FET_SW_P12V_STBY_PVDDQ_KLM")
		)
		(pad "2" smd rect
			(at 0 1.778 270)
			(size 1.27 1.016)
			(layers "B.Cu" "B.Mask" "B.Paste")
			(net "GND")
		)
		(zone
			(layer "B.Cu")
			(hatch none 0.5)
			(connect_pads
				(clearance 0)
			)
			(min_thickness 0.25)
			(keepout
				(tracks not_allowed)
				(vias allowed)
				(pads allowed)
				(copperpour not_allowed)
				(footprints allowed)
			)
			(placement
				(enabled no)
				(sheetname "")
			)
			(fill
				(thermal_gap 0.5)
				(thermal_bridge_width 0.5)
				(island_removal_mode 0)
			)
			(polygon
				(pts
					(xy 1.8542 -140.462) (xy 2.6162 -140.462) (xy 2.6162 -141.732) (xy 1.8542 -141.732)
				)
			)
		)
	)
)
